FILE_TYPE = CONNECTIVITY;
{Allegro Design Entry HDL 17.2-2016 S081 (4005846) 1/11/2022}
"PAGE_NUMBER" = 55;
0"NC";
1"M_E_CPU1_SA_CA<6:0>";
2"M_E_CPU1_SA_CS_N<3:0>";
3"M_E_CPU1_SA_DQS_DN<9:0>";
4"M_E_CPU1_SA_DQS_DP<9:0>";
5"M_E_CPU1_SB_CA<6:0>";
6"M_E_CPU1_SB_CS_N<3:0>";
7"M_E_CPU1_SB_DQS_DN<9:0>";
8"M_E_CPU1_SB_DQS_DP<9:0>";
9"M_E_CPU1_SB_CB<7:0>";
10"M_E_CPU1_SB_DQ<31:0>";
11"M_E_CPU1_SA_CB<7:0>";
12"M_E_CPU1_SA_DQ<31:0>";
13"M_E_CPU1_CLK_DP<1:0>";
14"M_E_CPU1_CLK_DN<1:0>";
15"M_E_CPU1_SA_DQ<7>";
16"M_E_CPU1_SA_DQ<6>";
17"M_E_CPU1_SA_DQ<5>";
18"M_E_CPU1_CLK_DN<1>";
19"M_E_CPU1_CLK_DN<0>";
20"M_E_CPU1_CLK_DP<1>";
21"M_E_CPU1_CLK_DP<0>";
22"M_E_CPU1_SA_DQ<31>";
23"M_E_CPU1_SA_DQ<30>";
24"M_E_CPU1_SA_DQ<29>";
25"M_E_CPU1_SA_DQ<28>";
26"M_E_CPU1_SA_DQ<27>";
27"M_E_CPU1_SA_DQ<26>";
28"M_E_CPU1_SA_DQ<25>";
29"M_E_CPU1_SA_DQ<24>";
30"M_E_CPU1_SA_DQ<23>";
31"M_E_CPU1_SA_DQ<22>";
32"M_E_CPU1_SA_DQ<21>";
33"M_E_CPU1_SA_DQ<20>";
34"M_E_CPU1_SA_DQ<19>";
35"M_E_CPU1_SA_DQ<18>";
36"M_E_CPU1_SA_DQ<17>";
37"M_E_CPU1_SA_DQ<16>";
38"M_E_CPU1_SA_DQ<15>";
39"M_E_CPU1_SA_DQ<14>";
40"M_E_CPU1_SA_DQ<13>";
41"M_E_CPU1_SA_DQ<12>";
42"M_E_CPU1_SA_DQ<11>";
43"M_E_CPU1_SA_DQ<10>";
44"M_E_CPU1_SA_DQ<9>";
45"M_E_CPU1_SA_DQ<8>";
46"M_E_CPU1_SA_DQ<4>";
47"M_E_CPU1_SA_DQ<3>";
48"M_E_CPU1_SA_DQ<2>";
49"M_E_CPU1_SA_DQ<1>";
50"M_E_CPU1_SA_DQ<0>";
51"M_E_CPU1_SA_CB<7>";
52"M_E_CPU1_SA_CB<6>";
53"M_E_CPU1_SA_CB<5>";
54"M_E_CPU1_SA_CB<4>";
55"M_E_CPU1_SA_CB<3>";
56"M_E_CPU1_SA_CB<2>";
57"M_E_CPU1_SA_CB<1>";
58"M_E_CPU1_SA_CB<0>";
59"M_E_CPU1_SB_DQ<31>";
60"M_E_CPU1_SB_DQ<30>";
61"M_E_CPU1_SB_DQ<29>";
62"M_E_CPU1_SB_DQ<28>";
63"M_E_CPU1_SB_DQ<27>";
64"M_E_CPU1_SB_DQ<26>";
65"M_E_CPU1_SB_DQ<25>";
66"M_E_CPU1_SB_DQ<24>";
67"M_E_CPU1_SB_DQ<23>";
68"M_E_CPU1_SB_DQ<22>";
69"M_E_CPU1_SB_DQ<21>";
70"M_E_CPU1_SB_DQ<20>";
71"M_E_CPU1_SB_DQ<19>";
72"M_E_CPU1_SB_DQ<18>";
73"M_E_CPU1_SB_DQ<17>";
74"M_E_CPU1_SB_DQ<16>";
75"M_E_CPU1_SB_DQ<15>";
76"M_E_CPU1_SB_DQ<14>";
77"M_E_CPU1_SB_DQ<13>";
78"M_E_CPU1_SB_DQ<12>";
79"M_E_CPU1_SB_DQ<11>";
80"M_E_CPU1_SB_DQ<10>";
81"M_E_CPU1_SB_DQ<9>";
82"M_E_CPU1_SB_DQ<8>";
83"M_E_CPU1_SB_DQ<7>";
84"M_E_CPU1_SB_DQ<6>";
85"M_E_CPU1_SB_DQ<5>";
86"M_E_CPU1_SB_DQ<4>";
87"M_E_CPU1_SB_DQ<3>";
88"M_E_CPU1_SB_DQ<2>";
89"M_E_CPU1_SB_DQ<1>";
90"M_E_CPU1_SB_DQ<0>";
91"M_E_CPU1_SB_CB<7>";
92"M_E_CPU1_SB_CB<6>";
93"M_E_CPU1_SB_CB<5>";
94"M_E_CPU1_SB_CB<4>";
95"M_E_CPU1_SB_CB<3>";
96"M_E_CPU1_SB_CB<2>";
97"M_E_CPU1_SB_CB<1>";
98"M_E_CPU1_SB_CB<0>";
99"M_E_CPU1_SB_PAR";
100"M_E_CPU1_SB_DQS_DP<0>";
101"M_E_CPU1_SB_DQS_DP<1>";
102"M_E_CPU1_SB_DQS_DP<2>";
103"M_E_CPU1_SB_DQS_DP<3>";
104"M_E_CPU1_SB_DQS_DP<4>";
105"M_E_CPU1_SB_DQS_DP<5>";
106"M_E_CPU1_SB_DQS_DP<6>";
107"M_E_CPU1_SB_DQS_DP<7>";
108"M_E_CPU1_SB_DQS_DP<8>";
109"M_E_CPU1_SB_DQS_DP<9>";
110"M_E_CPU1_SB_DQS_DN<0>";
111"M_E_CPU1_SB_DQS_DN<1>";
112"M_E_CPU1_SB_DQS_DN<2>";
113"M_E_CPU1_SB_DQS_DN<3>";
114"M_E_CPU1_SB_DQS_DN<4>";
115"M_E_CPU1_SB_DQS_DN<5>";
116"M_E_CPU1_SB_DQS_DN<6>";
117"M_E_CPU1_SB_DQS_DN<7>";
118"M_E_CPU1_SB_DQS_DN<8>";
119"M_E_CPU1_SB_DQS_DN<9>";
120"M_E_CPU1_SB_CS_N<0>";
121"M_E_CPU1_SB_CS_N<1>";
122"M_E_CPU1_SB_CS_N<2>";
123"M_E_CPU1_SB_CS_N<3>";
124"M_E_CPU1_SB_CA<0>";
125"M_E_CPU1_SB_CA<1>";
126"M_E_CPU1_SB_CA<2>";
127"M_E_CPU1_SB_CA<3>";
128"M_E_CPU1_SB_CA<4>";
129"M_E_CPU1_SB_CA<5>";
130"M_E_CPU1_SB_CA<6>";
131"M_E_CPU1_SA_PAR";
132"M_E_CPU1_SA_DQS_DP<0>";
133"M_E_CPU1_SA_DQS_DP<1>";
134"M_E_CPU1_SA_DQS_DP<2>";
135"M_E_CPU1_SA_DQS_DP<3>";
136"M_E_CPU1_SA_DQS_DP<4>";
137"M_E_CPU1_SA_DQS_DP<5>";
138"M_E_CPU1_SA_DQS_DP<6>";
139"M_E_CPU1_SA_DQS_DP<7>";
140"M_E_CPU1_SA_DQS_DP<8>";
141"M_E_CPU1_SA_DQS_DP<9>";
142"M_E_CPU1_SA_DQS_DN<0>";
143"M_E_CPU1_SA_DQS_DN<1>";
144"M_E_CPU1_SA_DQS_DN<2>";
145"M_E_CPU1_SA_DQS_DN<3>";
146"M_E_CPU1_SA_DQS_DN<4>";
147"M_E_CPU1_SA_DQS_DN<5>";
148"M_E_CPU1_SA_DQS_DN<6>";
149"M_E_CPU1_SA_DQS_DN<7>";
150"M_E_CPU1_SA_DQS_DN<8>";
151"M_E_CPU1_SA_DQS_DN<9>";
152"M_E_CPU1_SA_CS_N<0>";
153"M_E_CPU1_SA_CS_N<1>";
154"M_E_CPU1_SA_CS_N<2>";
155"M_E_CPU1_SA_CS_N<3>";
156"M_E_CPU1_SA_CA<0>";
157"M_E_CPU1_SA_CA<1>";
158"M_E_CPU1_SA_CA<2>";
159"M_E_CPU1_SA_CA<3>";
160"M_E_CPU1_SA_CA<4>";
161"M_E_CPU1_SA_CA<5>";
162"M_E_CPU1_SA_CA<6>";
163"M_E_CPU1_SB_RSP<0>";
164"M_E_CPU1_SB_RSP<1>";
165"M_E_CPU1_SA_RSP<0>";
166"M_E_CPU1_SA_RSP<1>";
167"M_E_CPU1_ALERT_N";
%"TAP"
"1","(-1075,25)","2","standard","I10";
;
CDS_LIB"standard"
BODY_TYPE"PLUMBING"
HDL_TAP"TRUE";
"B \NAC \NWC"9;
"S \NAC"
BN"0"98;
%"TAP"
"1","(2350,675)","0","standard","I100";
;
CDS_LIB"standard"
BODY_TYPE"PLUMBING"
HDL_TAP"TRUE";
"B \NAC \NWC"2;
"S \NAC"
BN"3"155;
%"TAP"
"1","(2350,525)","0","standard","I101";
;
CDS_LIB"standard"
BODY_TYPE"PLUMBING"
HDL_TAP"TRUE";
"B \NAC \NWC"2;
"S \NAC"
BN"0"152;
%"TAP"
"1","(2350,575)","0","standard","I102";
;
CDS_LIB"standard"
BODY_TYPE"PLUMBING"
HDL_TAP"TRUE";
"B \NAC \NWC"2;
"S \NAC"
BN"1"153;
%"TAP"
"1","(2350,925)","0","standard","I103";
;
CDS_LIB"standard"
BODY_TYPE"PLUMBING"
HDL_TAP"TRUE";
"B \NAC \NWC"5;
"S \NAC"
BN"1"125;
%"TAP"
"1","(2350,875)","0","standard","I104";
;
CDS_LIB"standard"
BODY_TYPE"PLUMBING"
HDL_TAP"TRUE";
"B \NAC \NWC"5;
"S \NAC"
BN"0"124;
%"TAP"
"1","(2350,975)","0","standard","I105";
;
CDS_LIB"standard"
BODY_TYPE"PLUMBING"
HDL_TAP"TRUE";
"B \NAC \NWC"5;
"S \NAC"
BN"2"126;
%"TAP"
"1","(2350,1175)","0","standard","I106";
;
CDS_LIB"standard"
BODY_TYPE"PLUMBING"
HDL_TAP"TRUE";
"B \NAC \NWC"5;
"S \NAC"
BN"6"130;
%"TAP"
"1","(2350,1125)","0","standard","I107";
;
CDS_LIB"standard"
BODY_TYPE"PLUMBING"
HDL_TAP"TRUE";
"B \NAC \NWC"5;
"S \NAC"
BN"5"129;
%"TAP"
"1","(2350,1075)","0","standard","I108";
;
CDS_LIB"standard"
BODY_TYPE"PLUMBING"
HDL_TAP"TRUE";
"B \NAC \NWC"5;
"S \NAC"
BN"4"128;
%"TAP"
"1","(2350,1025)","0","standard","I109";
;
CDS_LIB"standard"
BODY_TYPE"PLUMBING"
HDL_TAP"TRUE";
"B \NAC \NWC"5;
"S \NAC"
BN"3"127;
%"TAP"
"1","(-1075,75)","2","standard","I11";
;
CDS_LIB"standard"
BODY_TYPE"PLUMBING"
HDL_TAP"TRUE";
"B \NAC \NWC"9;
"S \NAC"
BN"1"97;
%"TAP"
"1","(2350,1375)","0","standard","I110";
;
CDS_LIB"standard"
BODY_TYPE"PLUMBING"
HDL_TAP"TRUE";
"B \NAC \NWC"1;
"S \NAC"
BN"0"156;
%"TAP"
"1","(2350,1425)","0","standard","I111";
;
CDS_LIB"standard"
BODY_TYPE"PLUMBING"
HDL_TAP"TRUE";
"B \NAC \NWC"1;
"S \NAC"
BN"1"157;
%"TAP"
"1","(2350,1475)","0","standard","I112";
;
CDS_LIB"standard"
BODY_TYPE"PLUMBING"
HDL_TAP"TRUE";
"B \NAC \NWC"1;
"S \NAC"
BN"2"158;
%"TAP"
"1","(2350,1675)","0","standard","I113";
;
CDS_LIB"standard"
BODY_TYPE"PLUMBING"
HDL_TAP"TRUE";
"B \NAC \NWC"1;
"S \NAC"
BN"6"162;
%"TAP"
"1","(2350,1625)","0","standard","I114";
;
CDS_LIB"standard"
BODY_TYPE"PLUMBING"
HDL_TAP"TRUE";
"B \NAC \NWC"1;
"S \NAC"
BN"5"161;
%"TAP"
"1","(2350,1525)","0","standard","I115";
;
CDS_LIB"standard"
BODY_TYPE"PLUMBING"
HDL_TAP"TRUE";
"B \NAC \NWC"1;
"S \NAC"
BN"3"159;
%"TAP"
"1","(2350,1575)","0","standard","I116";
;
CDS_LIB"standard"
BODY_TYPE"PLUMBING"
HDL_TAP"TRUE";
"B \NAC \NWC"1;
"S \NAC"
BN"4"160;
%"TAP"
"1","(2350,1975)","0","standard","I117";
;
CDS_LIB"standard"
BODY_TYPE"PLUMBING"
HDL_TAP"TRUE";
"B \NAC \NWC"7;
"S \NAC"
BN"3"113;
%"TAP"
"1","(2350,1875)","0","standard","I118";
;
CDS_LIB"standard"
BODY_TYPE"PLUMBING"
HDL_TAP"TRUE";
"B \NAC \NWC"7;
"S \NAC"
BN"1"111;
%"TAP"
"1","(2350,1925)","0","standard","I119";
;
CDS_LIB"standard"
BODY_TYPE"PLUMBING"
HDL_TAP"TRUE";
"B \NAC \NWC"7;
"S \NAC"
BN"2"112;
%"TAP"
"1","(-1075,125)","2","standard","I12";
;
CDS_LIB"standard"
BODY_TYPE"PLUMBING"
HDL_TAP"TRUE";
"B \NAC \NWC"9;
"S \NAC"
BN"2"96;
%"TAP"
"1","(2350,1825)","0","standard","I120";
;
CDS_LIB"standard"
BODY_TYPE"PLUMBING"
HDL_TAP"TRUE";
"B \NAC \NWC"7;
"S \NAC"
BN"0"110;
%"TAP"
"1","(2350,2075)","0","standard","I129";
;
CDS_LIB"standard"
BODY_TYPE"PLUMBING"
HDL_TAP"TRUE";
"B \NAC \NWC"7;
"S \NAC"
BN"5"115;
%"TAP"
"1","(-1075,175)","2","standard","I13";
;
CDS_LIB"standard"
BODY_TYPE"PLUMBING"
HDL_TAP"TRUE";
"B \NAC \NWC"9;
"S \NAC"
BN"3"95;
%"TAP"
"1","(2350,2025)","0","standard","I130";
;
CDS_LIB"standard"
BODY_TYPE"PLUMBING"
HDL_TAP"TRUE";
"B \NAC \NWC"7;
"S \NAC"
BN"4"114;
%"TAP"
"1","(2350,2125)","0","standard","I131";
;
CDS_LIB"standard"
BODY_TYPE"PLUMBING"
HDL_TAP"TRUE";
"B \NAC \NWC"7;
"S \NAC"
BN"6"116;
%"TAP"
"1","(2350,2175)","0","standard","I132";
;
CDS_LIB"standard"
BODY_TYPE"PLUMBING"
HDL_TAP"TRUE";
"B \NAC \NWC"7;
"S \NAC"
BN"7"117;
%"TAP"
"1","(2350,2275)","0","standard","I133";
;
CDS_LIB"standard"
BODY_TYPE"PLUMBING"
HDL_TAP"TRUE";
"B \NAC \NWC"7;
"S \NAC"
BN"9"119;
%"TAP"
"1","(2350,2225)","0","standard","I134";
;
CDS_LIB"standard"
BODY_TYPE"PLUMBING"
HDL_TAP"TRUE";
"B \NAC \NWC"7;
"S \NAC"
BN"8"118;
%"TAP"
"1","(2350,2425)","0","standard","I135";
;
CDS_LIB"standard"
BODY_TYPE"PLUMBING"
HDL_TAP"TRUE";
"B \NAC \NWC"8;
"S \NAC"
BN"1"101;
%"TAP"
"1","(2350,2475)","0","standard","I136";
;
CDS_LIB"standard"
BODY_TYPE"PLUMBING"
HDL_TAP"TRUE";
"B \NAC \NWC"8;
"S \NAC"
BN"2"102;
%"TAP"
"1","(2350,2525)","0","standard","I137";
;
CDS_LIB"standard"
BODY_TYPE"PLUMBING"
HDL_TAP"TRUE";
"B \NAC \NWC"8;
"S \NAC"
BN"3"103;
%"TAP"
"1","(2350,2375)","0","standard","I138";
;
CDS_LIB"standard"
BODY_TYPE"PLUMBING"
HDL_TAP"TRUE";
"B \NAC \NWC"8;
"S \NAC"
BN"0"100;
%"TAP"
"1","(2350,2675)","0","standard","I139";
;
CDS_LIB"standard"
BODY_TYPE"PLUMBING"
HDL_TAP"TRUE";
"B \NAC \NWC"8;
"S \NAC"
BN"6"106;
%"TAP"
"1","(-1075,225)","2","standard","I14";
;
CDS_LIB"standard"
BODY_TYPE"PLUMBING"
HDL_TAP"TRUE";
"B \NAC \NWC"9;
"S \NAC"
BN"4"94;
%"TAP"
"1","(2350,2725)","0","standard","I140";
;
CDS_LIB"standard"
BODY_TYPE"PLUMBING"
HDL_TAP"TRUE";
"B \NAC \NWC"8;
"S \NAC"
BN"7"107;
%"TAP"
"1","(2350,2775)","0","standard","I141";
;
CDS_LIB"standard"
BODY_TYPE"PLUMBING"
HDL_TAP"TRUE";
"B \NAC \NWC"8;
"S \NAC"
BN"8"108;
%"TAP"
"1","(2350,2625)","0","standard","I142";
;
CDS_LIB"standard"
BODY_TYPE"PLUMBING"
HDL_TAP"TRUE";
"B \NAC \NWC"8;
"S \NAC"
BN"5"105;
%"TAP"
"1","(2350,2575)","0","standard","I143";
;
CDS_LIB"standard"
BODY_TYPE"PLUMBING"
HDL_TAP"TRUE";
"B \NAC \NWC"8;
"S \NAC"
BN"4"104;
%"TAP"
"1","(2350,2825)","0","standard","I144";
;
CDS_LIB"standard"
BODY_TYPE"PLUMBING"
HDL_TAP"TRUE";
"B \NAC \NWC"8;
"S \NAC"
BN"9"109;
%"TAP"
"1","(2350,2975)","0","standard","I145";
;
CDS_LIB"standard"
BODY_TYPE"PLUMBING"
HDL_TAP"TRUE";
"B \NAC \NWC"3;
"S \NAC"
BN"0"142;
%"TAP"
"1","(2350,3025)","0","standard","I146";
;
CDS_LIB"standard"
BODY_TYPE"PLUMBING"
HDL_TAP"TRUE";
"B \NAC \NWC"3;
"S \NAC"
BN"1"143;
%"TAP"
"1","(2350,3225)","0","standard","I147";
;
CDS_LIB"standard"
BODY_TYPE"PLUMBING"
HDL_TAP"TRUE";
"B \NAC \NWC"3;
"S \NAC"
BN"5"147;
%"TAP"
"1","(2350,3275)","0","standard","I148";
;
CDS_LIB"standard"
BODY_TYPE"PLUMBING"
HDL_TAP"TRUE";
"B \NAC \NWC"3;
"S \NAC"
BN"6"148;
%"TAP"
"1","(2350,3175)","0","standard","I149";
;
CDS_LIB"standard"
BODY_TYPE"PLUMBING"
HDL_TAP"TRUE";
"B \NAC \NWC"3;
"S \NAC"
BN"4"146;
%"TAP"
"1","(-1075,275)","2","standard","I15";
;
CDS_LIB"standard"
BODY_TYPE"PLUMBING"
HDL_TAP"TRUE";
"B \NAC \NWC"9;
"S \NAC"
BN"5"93;
%"TAP"
"1","(2350,3125)","0","standard","I150";
;
CDS_LIB"standard"
BODY_TYPE"PLUMBING"
HDL_TAP"TRUE";
"B \NAC \NWC"3;
"S \NAC"
BN"3"145;
%"TAP"
"1","(2350,3075)","0","standard","I151";
;
CDS_LIB"standard"
BODY_TYPE"PLUMBING"
HDL_TAP"TRUE";
"B \NAC \NWC"3;
"S \NAC"
BN"2"144;
%"TAP"
"1","(2350,3325)","0","standard","I152";
;
CDS_LIB"standard"
BODY_TYPE"PLUMBING"
HDL_TAP"TRUE";
"B \NAC \NWC"3;
"S \NAC"
BN"7"149;
%"TAP"
"1","(2350,3525)","0","standard","I153";
;
CDS_LIB"standard"
BODY_TYPE"PLUMBING"
HDL_TAP"TRUE";
"B \NAC \NWC"4;
"S \NAC"
BN"0"132;
%"TAP"
"1","(2350,3425)","0","standard","I154";
;
CDS_LIB"standard"
BODY_TYPE"PLUMBING"
HDL_TAP"TRUE";
"B \NAC \NWC"3;
"S \NAC"
BN"9"151;
%"TAP"
"1","(2350,3375)","0","standard","I155";
;
CDS_LIB"standard"
BODY_TYPE"PLUMBING"
HDL_TAP"TRUE";
"B \NAC \NWC"3;
"S \NAC"
BN"8"150;
%"TAP"
"1","(2350,3775)","0","standard","I156";
;
CDS_LIB"standard"
BODY_TYPE"PLUMBING"
HDL_TAP"TRUE";
"B \NAC \NWC"4;
"S \NAC"
BN"5"137;
%"TAP"
"1","(2350,3675)","0","standard","I157";
;
CDS_LIB"standard"
BODY_TYPE"PLUMBING"
HDL_TAP"TRUE";
"B \NAC \NWC"4;
"S \NAC"
BN"3"135;
%"TAP"
"1","(2350,3725)","0","standard","I158";
;
CDS_LIB"standard"
BODY_TYPE"PLUMBING"
HDL_TAP"TRUE";
"B \NAC \NWC"4;
"S \NAC"
BN"4"136;
%"TAP"
"1","(2350,3575)","0","standard","I159";
;
CDS_LIB"standard"
BODY_TYPE"PLUMBING"
HDL_TAP"TRUE";
"B \NAC \NWC"4;
"S \NAC"
BN"1"133;
%"TAP"
"1","(-1075,325)","2","standard","I16";
;
CDS_LIB"standard"
BODY_TYPE"PLUMBING"
HDL_TAP"TRUE";
"B \NAC \NWC"9;
"S \NAC"
BN"6"92;
%"TAP"
"1","(2350,3625)","0","standard","I160";
;
CDS_LIB"standard"
BODY_TYPE"PLUMBING"
HDL_TAP"TRUE";
"B \NAC \NWC"4;
"S \NAC"
BN"2"134;
%"TAP"
"1","(2350,3975)","0","standard","I161";
;
CDS_LIB"standard"
BODY_TYPE"PLUMBING"
HDL_TAP"TRUE";
"B \NAC \NWC"4;
"S \NAC"
BN"9"141;
%"TAP"
"1","(2350,3925)","0","standard","I162";
;
CDS_LIB"standard"
BODY_TYPE"PLUMBING"
HDL_TAP"TRUE";
"B \NAC \NWC"4;
"S \NAC"
BN"8"140;
%"TAP"
"1","(2350,3825)","0","standard","I163";
;
CDS_LIB"standard"
BODY_TYPE"PLUMBING"
HDL_TAP"TRUE";
"B \NAC \NWC"4;
"S \NAC"
BN"6"138;
%"TAP"
"1","(2350,3875)","0","standard","I164";
;
CDS_LIB"standard"
BODY_TYPE"PLUMBING"
HDL_TAP"TRUE";
"B \NAC \NWC"4;
"S \NAC"
BN"7"139;
%"TAP"
"1","(-1075,375)","2","standard","I17";
;
CDS_LIB"standard"
BODY_TYPE"PLUMBING"
HDL_TAP"TRUE";
"B \NAC \NWC"9;
"S \NAC"
BN"7"91;
%"TAP"
"1","(-1075,425)","2","standard","I18";
;
CDS_LIB"standard"
BODY_TYPE"PLUMBING"
HDL_TAP"TRUE";
"B \NAC \NWC"10;
"S \NAC"
BN"0"90;
%"TAP"
"1","(-1075,475)","2","standard","I19";
;
CDS_LIB"standard"
BODY_TYPE"PLUMBING"
HDL_TAP"TRUE";
"B \NAC \NWC"10;
"S \NAC"
BN"1"89;
%"TAP"
"1","(-1075,525)","2","standard","I20";
;
CDS_LIB"standard"
BODY_TYPE"PLUMBING"
HDL_TAP"TRUE";
"B \NAC \NWC"10;
"S \NAC"
BN"2"88;
%"TAP"
"1","(-1075,575)","2","standard","I21";
;
CDS_LIB"standard"
BODY_TYPE"PLUMBING"
HDL_TAP"TRUE";
"B \NAC \NWC"10;
"S \NAC"
BN"3"87;
%"TAP"
"1","(-1075,675)","2","standard","I22";
;
CDS_LIB"standard"
BODY_TYPE"PLUMBING"
HDL_TAP"TRUE";
"B \NAC \NWC"10;
"S \NAC"
BN"5"85;
%"TAP"
"1","(-1075,625)","2","standard","I23";
;
CDS_LIB"standard"
BODY_TYPE"PLUMBING"
HDL_TAP"TRUE";
"B \NAC \NWC"10;
"S \NAC"
BN"4"86;
%"TAP"
"1","(-1075,725)","2","standard","I24";
;
CDS_LIB"standard"
BODY_TYPE"PLUMBING"
HDL_TAP"TRUE";
"B \NAC \NWC"10;
"S \NAC"
BN"6"84;
%"TAP"
"1","(-1075,775)","2","standard","I25";
;
CDS_LIB"standard"
BODY_TYPE"PLUMBING"
HDL_TAP"TRUE";
"B \NAC \NWC"10;
"S \NAC"
BN"7"83;
%"TAP"
"1","(-1075,825)","2","standard","I26";
;
CDS_LIB"standard"
BODY_TYPE"PLUMBING"
HDL_TAP"TRUE";
"B \NAC \NWC"10;
"S \NAC"
BN"8"82;
%"TAP"
"1","(-1075,925)","2","standard","I27";
;
CDS_LIB"standard"
BODY_TYPE"PLUMBING"
HDL_TAP"TRUE";
"B \NAC \NWC"10;
"S \NAC"
BN"10"80;
%"TAP"
"1","(-1075,875)","2","standard","I28";
;
CDS_LIB"standard"
BODY_TYPE"PLUMBING"
HDL_TAP"TRUE";
"B \NAC \NWC"10;
"S \NAC"
BN"9"81;
%"TAP"
"1","(-1075,975)","2","standard","I29";
;
CDS_LIB"standard"
BODY_TYPE"PLUMBING"
HDL_TAP"TRUE";
"B \NAC \NWC"10;
"S \NAC"
BN"11"79;
%"TAP"
"1","(-1075,-175)","2","standard","I3";
;
CDS_LIB"standard"
BODY_TYPE"PLUMBING"
HDL_TAP"TRUE";
"B \NAC \NWC"14;
"S \NAC"
BN"1"18;
%"TAP"
"1","(-1075,1025)","2","standard","I30";
;
CDS_LIB"standard"
BODY_TYPE"PLUMBING"
HDL_TAP"TRUE";
"B \NAC \NWC"10;
"S \NAC"
BN"12"78;
%"TAP"
"1","(-1075,1075)","2","standard","I31";
;
CDS_LIB"standard"
BODY_TYPE"PLUMBING"
HDL_TAP"TRUE";
"B \NAC \NWC"10;
"S \NAC"
BN"13"77;
%"TAP"
"1","(-1075,1125)","2","standard","I32";
;
CDS_LIB"standard"
BODY_TYPE"PLUMBING"
HDL_TAP"TRUE";
"B \NAC \NWC"10;
"S \NAC"
BN"14"76;
%"TAP"
"1","(-1075,1175)","2","standard","I33";
;
CDS_LIB"standard"
BODY_TYPE"PLUMBING"
HDL_TAP"TRUE";
"B \NAC \NWC"10;
"S \NAC"
BN"15"75;
%"TAP"
"1","(-1075,1225)","2","standard","I34";
;
CDS_LIB"standard"
BODY_TYPE"PLUMBING"
HDL_TAP"TRUE";
"B \NAC \NWC"10;
"S \NAC"
BN"16"74;
%"TAP"
"1","(-1075,1325)","2","standard","I35";
;
CDS_LIB"standard"
BODY_TYPE"PLUMBING"
HDL_TAP"TRUE";
"B \NAC \NWC"10;
"S \NAC"
BN"18"72;
%"TAP"
"1","(-1075,1275)","2","standard","I36";
;
CDS_LIB"standard"
BODY_TYPE"PLUMBING"
HDL_TAP"TRUE";
"B \NAC \NWC"10;
"S \NAC"
BN"17"73;
%"TAP"
"1","(-1075,1375)","2","standard","I37";
;
CDS_LIB"standard"
BODY_TYPE"PLUMBING"
HDL_TAP"TRUE";
"B \NAC \NWC"10;
"S \NAC"
BN"19"71;
%"TAP"
"1","(-1075,1425)","2","standard","I38";
;
CDS_LIB"standard"
BODY_TYPE"PLUMBING"
HDL_TAP"TRUE";
"B \NAC \NWC"10;
"S \NAC"
BN"20"70;
%"TAP"
"1","(-1075,1475)","2","standard","I39";
;
CDS_LIB"standard"
BODY_TYPE"PLUMBING"
HDL_TAP"TRUE";
"B \NAC \NWC"10;
"S \NAC"
BN"21"69;
%"TAP"
"1","(-1075,-225)","2","standard","I4";
;
CDS_LIB"standard"
BODY_TYPE"PLUMBING"
HDL_TAP"TRUE";
"B \NAC \NWC"14;
"S \NAC"
BN"0"19;
%"TAP"
"1","(-1075,1575)","2","standard","I40";
;
CDS_LIB"standard"
BODY_TYPE"PLUMBING"
HDL_TAP"TRUE";
"B \NAC \NWC"10;
"S \NAC"
BN"23"67;
%"TAP"
"1","(-1075,1525)","2","standard","I41";
;
CDS_LIB"standard"
BODY_TYPE"PLUMBING"
HDL_TAP"TRUE";
"B \NAC \NWC"10;
"S \NAC"
BN"22"68;
%"TAP"
"1","(-1075,1625)","2","standard","I42";
;
CDS_LIB"standard"
BODY_TYPE"PLUMBING"
HDL_TAP"TRUE";
"B \NAC \NWC"10;
"S \NAC"
BN"24"66;
%"TAP"
"1","(-1075,1675)","2","standard","I43";
;
CDS_LIB"standard"
BODY_TYPE"PLUMBING"
HDL_TAP"TRUE";
"B \NAC \NWC"10;
"S \NAC"
BN"25"65;
%"TAP"
"1","(-1075,1725)","2","standard","I44";
;
CDS_LIB"standard"
BODY_TYPE"PLUMBING"
HDL_TAP"TRUE";
"B \NAC \NWC"10;
"S \NAC"
BN"26"64;
%"TAP"
"1","(-1075,1825)","2","standard","I45";
;
CDS_LIB"standard"
BODY_TYPE"PLUMBING"
HDL_TAP"TRUE";
"B \NAC \NWC"10;
"S \NAC"
BN"28"62;
%"TAP"
"1","(-1075,1775)","2","standard","I46";
;
CDS_LIB"standard"
BODY_TYPE"PLUMBING"
HDL_TAP"TRUE";
"B \NAC \NWC"10;
"S \NAC"
BN"27"63;
%"TAP"
"1","(-1075,1875)","2","standard","I47";
;
CDS_LIB"standard"
BODY_TYPE"PLUMBING"
HDL_TAP"TRUE";
"B \NAC \NWC"10;
"S \NAC"
BN"29"61;
%"TAP"
"1","(-1075,1925)","2","standard","I48";
;
CDS_LIB"standard"
BODY_TYPE"PLUMBING"
HDL_TAP"TRUE";
"B \NAC \NWC"10;
"S \NAC"
BN"30"60;
%"TAP"
"1","(-1075,1975)","2","standard","I49";
;
CDS_LIB"standard"
BODY_TYPE"PLUMBING"
HDL_TAP"TRUE";
"B \NAC \NWC"10;
"S \NAC"
BN"31"59;
%"TAP"
"1","(-1075,-125)","2","standard","I5";
;
CDS_LIB"standard"
BODY_TYPE"PLUMBING"
HDL_TAP"TRUE";
"B \NAC \NWC"13;
"S \NAC"
BN"0"21;
%"TAP"
"1","(-1075,2075)","2","standard","I52";
;
CDS_LIB"standard"
BODY_TYPE"PLUMBING"
HDL_TAP"TRUE";
"B \NAC \NWC"11;
"S \NAC"
BN"1"57;
%"TAP"
"1","(-1075,2025)","2","standard","I53";
;
CDS_LIB"standard"
BODY_TYPE"PLUMBING"
HDL_TAP"TRUE";
"B \NAC \NWC"11;
"S \NAC"
BN"0"58;
%"TAP"
"1","(-1075,2125)","2","standard","I54";
;
CDS_LIB"standard"
BODY_TYPE"PLUMBING"
HDL_TAP"TRUE";
"B \NAC \NWC"11;
"S \NAC"
BN"2"56;
%"TAP"
"1","(-1075,2225)","2","standard","I55";
;
CDS_LIB"standard"
BODY_TYPE"PLUMBING"
HDL_TAP"TRUE";
"B \NAC \NWC"11;
"S \NAC"
BN"4"54;
%"TAP"
"1","(-1075,2175)","2","standard","I56";
;
CDS_LIB"standard"
BODY_TYPE"PLUMBING"
HDL_TAP"TRUE";
"B \NAC \NWC"11;
"S \NAC"
BN"3"55;
%"TAP"
"1","(-1075,2275)","2","standard","I57";
;
CDS_LIB"standard"
BODY_TYPE"PLUMBING"
HDL_TAP"TRUE";
"B \NAC \NWC"11;
"S \NAC"
BN"5"53;
%"TAP"
"1","(-1075,2325)","2","standard","I58";
;
CDS_LIB"standard"
BODY_TYPE"PLUMBING"
HDL_TAP"TRUE";
"B \NAC \NWC"11;
"S \NAC"
BN"6"52;
%"TAP"
"1","(-1075,2375)","2","standard","I59";
;
CDS_LIB"standard"
BODY_TYPE"PLUMBING"
HDL_TAP"TRUE";
"B \NAC \NWC"11;
"S \NAC"
BN"7"51;
%"TAP"
"1","(-1075,-75)","2","standard","I6";
;
CDS_LIB"standard"
BODY_TYPE"PLUMBING"
HDL_TAP"TRUE";
"B \NAC \NWC"13;
"S \NAC"
BN"1"20;
%"TAP"
"1","(-1075,2425)","2","standard","I60";
;
CDS_LIB"standard"
BODY_TYPE"PLUMBING"
HDL_TAP"TRUE";
"B \NAC \NWC"12;
"S \NAC"
BN"0"50;
%"TAP"
"1","(-1075,2475)","2","standard","I61";
;
CDS_LIB"standard"
BODY_TYPE"PLUMBING"
HDL_TAP"TRUE";
"B \NAC \NWC"12;
"S \NAC"
BN"1"49;
%"TAP"
"1","(-1075,2525)","2","standard","I62";
;
CDS_LIB"standard"
BODY_TYPE"PLUMBING"
HDL_TAP"TRUE";
"B \NAC \NWC"12;
"S \NAC"
BN"2"48;
%"TAP"
"1","(-1075,2575)","2","standard","I63";
;
CDS_LIB"standard"
BODY_TYPE"PLUMBING"
HDL_TAP"TRUE";
"B \NAC \NWC"12;
"S \NAC"
BN"3"47;
%"TAP"
"1","(-1075,2625)","2","standard","I64";
;
CDS_LIB"standard"
BODY_TYPE"PLUMBING"
HDL_TAP"TRUE";
"B \NAC \NWC"12;
"S \NAC"
BN"4"46;
%"TAP"
"1","(-1075,2725)","2","standard","I65";
;
CDS_LIB"standard"
BODY_TYPE"PLUMBING"
HDL_TAP"TRUE";
"B \NAC \NWC"12;
"S \NAC"
BN"6"16;
%"TAP"
"1","(-1075,2675)","2","standard","I66";
;
CDS_LIB"standard"
BODY_TYPE"PLUMBING"
HDL_TAP"TRUE";
"B \NAC \NWC"12;
"S \NAC"
BN"5"17;
%"TAP"
"1","(-1075,2775)","2","standard","I67";
;
CDS_LIB"standard"
BODY_TYPE"PLUMBING"
HDL_TAP"TRUE";
"B \NAC \NWC"12;
"S \NAC"
BN"7"15;
%"TAP"
"1","(-1075,2825)","2","standard","I68";
;
CDS_LIB"standard"
BODY_TYPE"PLUMBING"
HDL_TAP"TRUE";
"B \NAC \NWC"12;
"S \NAC"
BN"8"45;
%"TAP"
"1","(-1075,2875)","2","standard","I69";
;
CDS_LIB"standard"
BODY_TYPE"PLUMBING"
HDL_TAP"TRUE";
"B \NAC \NWC"12;
"S \NAC"
BN"9"44;
%"SOCKET4677_AZIF0045P001C01CS"
"12","(650,1875)","0","pure_quanta","I7";
;
PART_NUMBER"DGA^7000023"
PART_TYPE"SMLF"
MATERIAL"IO"
VALUE"SOCKET4677_AZIF0045-P001C01CS"
$LOCATION"U1"
CDS_LIB"pure_quanta"
NEEDS_NO_SIZE"TRUE"
CDS_LMAN_SYM_OUTLINE"-1100,2250,1050,-2250"
CDS_LOCATION"U1"
$SEC"12"
CDS_SEC"12";
"DDR4_SB_PAR"
$PN"EP42"99;
"DDR4_SB_ECC0"
$PN"EL35"98;
"DDR4_SB_ECC1"
$PN"EM34"97;
"DDR4_SB_ECC2"
$PN"ER35"96;
"DDR4_SB_ECC3"
$PN"EP34"95;
"DDR4_SB_ECC4"
$PN"EM38"94;
"DDR4_SB_ECC5"
$PN"EL37"93;
"DDR4_SB_ECC6"
$PN"EP38"92;
"DDR4_SB_ECC7"
$PN"ER37"91;
"DDR4_SB_DQS_DP0"
$PN"EC27"100;
"DDR4_SB_DQS_DP1"
$PN"EM30"101;
"DDR4_SB_DQS_DP2"
$PN"EM24"102;
"DDR4_SB_DQS_DP3"
$PN"EM18"103;
"DDR4_SB_DQS_DP4"
$PN"EP36"104;
"DDR4_SB_DQS_DP5"
$PN"EG27"105;
"DDR4_SB_DQS_DP6"
$PN"EP30"106;
"DDR4_SB_DQS_DP7"
$PN"EP24"107;
"DDR4_SB_DQS_DP8"
$PN"EP18"108;
"DDR4_SB_DQS_DP9"
$PN"EM36"109;
"DDR4_SB_DQS_DN0 \B"
$PN"EE27"110;
"DDR4_SB_DQS_DN1 \B"
$PN"EK30"111;
"DDR4_SB_DQS_DN2 \B"
$PN"EK24"112;
"DDR4_SB_DQS_DN3 \B"
$PN"EK18"113;
"DDR4_SB_DQS_DN4 \B"
$PN"ET36"114;
"DDR4_SB_DQS_DN5 \B"
$PN"EJ27"115;
"DDR4_SB_DQS_DN6 \B"
$PN"ET30"116;
"DDR4_SB_DQS_DN7 \B"
$PN"ET24"117;
"DDR4_SB_DQS_DN8 \B"
$PN"ET18"118;
"DDR4_SB_DQS_DN9 \B"
$PN"EK36"119;
"DDR4_SB_DQ0"
$PN"EE29"90;
"DDR4_SB_DQ1"
$PN"ED28"89;
"DDR4_SB_DQ2"
$PN"EG29"88;
"DDR4_SB_DQ3"
$PN"EH28"87;
"DDR4_SB_DQ4"
$PN"ED26"86;
"DDR4_SB_DQ5"
$PN"EE25"85;
"DDR4_SB_DQ6"
$PN"EH26"84;
"DDR4_SB_DQ7"
$PN"EG25"83;
"DDR4_SB_DQ8"
$PN"EM32"82;
"DDR4_SB_DQ9"
$PN"EL31"81;
"DDR4_SB_DQ10"
$PN"EP32"80;
"DDR4_SB_DQ11"
$PN"ER31"79;
"DDR4_SB_DQ12"
$PN"EL29"78;
"DDR4_SB_DQ13"
$PN"EM28"77;
"DDR4_SB_DQ14"
$PN"ER29"76;
"DDR4_SB_DQ15"
$PN"EP28"75;
"DDR4_SB_DQ16"
$PN"EM26"74;
"DDR4_SB_DQ17"
$PN"EL25"73;
"DDR4_SB_DQ18"
$PN"EP26"72;
"DDR4_SB_DQ19"
$PN"ER25"71;
"DDR4_SB_DQ20"
$PN"EL23"70;
"DDR4_SB_DQ21"
$PN"EM22"69;
"DDR4_SB_DQ22"
$PN"ER23"68;
"DDR4_SB_DQ23"
$PN"EP22"67;
"DDR4_SB_DQ24"
$PN"EM20"66;
"DDR4_SB_DQ25"
$PN"EL19"65;
"DDR4_SB_DQ26"
$PN"EP20"64;
"DDR4_SB_DQ27"
$PN"ER19"63;
"DDR4_SB_DQ28"
$PN"EL17"62;
"DDR4_SB_DQ29"
$PN"EM16"61;
"DDR4_SB_DQ30"
$PN"ER17"60;
"DDR4_SB_DQ31"
$PN"EP16"59;
"DDR4_SB_CS_N0 \B"
$PN"EP40"120;
"DDR4_SB_CS_N1 \B"
$PN"ET40"121;
"DDR4_SB_CS_N2 \B"
$PN"EM40"122;
"DDR4_SB_CS_N3 \B"
$PN"EL41"123;
"DDR4_SB_CA0"
$PN"EG43"124;
"DDR4_SB_CA1"
$PN"EH44"125;
"DDR4_SB_CA2"
$PN"EM44"126;
"DDR4_SB_CA3"
$PN"EP44"127;
"DDR4_SB_CA4"
$PN"EL43"128;
"DDR4_SB_CA5"
$PN"ET42"129;
"DDR4_SB_CA6"
$PN"EK42"130;
"DDR4_SA_PAR"
$PN"EE43"131;
"DDR4_SA_ECC0"
$PN"EM57"58;
"DDR4_SA_ECC1"
$PN"EL56"57;
"DDR4_SA_ECC2"
$PN"EP57"56;
"DDR4_SA_ECC3"
$PN"ER56"55;
"DDR4_SA_ECC4"
$PN"EL54"54;
"DDR4_SA_ECC5"
$PN"EM53"53;
"DDR4_SA_ECC6"
$PN"ER54"52;
"DDR4_SA_ECC7"
$PN"EP53"51;
"DDR4_SA_DQS_DP0"
$PN"EN76"132;
"DDR4_SA_DQS_DP1"
$PN"EE70"133;
"DDR4_SA_DQS_DP2"
$PN"EL68"134;
"DDR4_SA_DQS_DP3"
$PN"EM61"135;
"DDR4_SA_DQS_DP4"
$PN"EK55"136;
"DDR4_SA_DQS_DP5"
$PN"EN74"137;
"DDR4_SA_DQS_DP6"
$PN"EG70"138;
"DDR4_SA_DQS_DP7"
$PN"EM67"139;
"DDR4_SA_DQS_DP8"
$PN"EP61"140;
"DDR4_SA_DQS_DP9"
$PN"EP55"141;
"DDR4_SA_DQS_DN0 \B"
$PN"EP75"142;
"DDR4_SA_DQS_DN1 \B"
$PN"EC70"143;
"DDR4_SA_DQS_DN2 \B"
$PN"EK67"144;
"DDR4_SA_DQS_DN3 \B"
$PN"EK61"145;
"DDR4_SA_DQS_DN4 \B"
$PN"EM55"146;
"DDR4_SA_DQS_DN5 \B"
$PN"EM75"147;
"DDR4_SA_DQS_DN6 \B"
$PN"EJ70"148;
"DDR4_SA_DQS_DN7 \B"
$PN"EN68"149;
"DDR4_SA_DQS_DN8 \B"
$PN"ET61"150;
"DDR4_SA_DQS_DN9 \B"
$PN"ET55"151;
"DDR4_SA_DQ0"
$PN"EL78"50;
"DDR4_SA_DQ1"
$PN"EM77"49;
"DDR4_SA_DQ2"
$PN"EP79"48;
"DDR4_SA_DQ3"
$PN"ER76"47;
"DDR4_SA_DQ4"
$PN"EL74"46;
"DDR4_SA_DQ5"
$PN"EK73"17;
"DDR4_SA_DQ6"
$PN"EP73"16;
"DDR4_SA_DQ7"
$PN"ER72"15;
"DDR4_SA_DQ8"
$PN"EE72"45;
"DDR4_SA_DQ9"
$PN"ED71"44;
"DDR4_SA_DQ10"
$PN"EG72"43;
"DDR4_SA_DQ11"
$PN"EH71"42;
"DDR4_SA_DQ12"
$PN"ED69"41;
"DDR4_SA_DQ13"
$PN"EE68"40;
"DDR4_SA_DQ14"
$PN"EH69"39;
"DDR4_SA_DQ15"
$PN"EG68"38;
"DDR4_SA_DQ16"
$PN"EM71"37;
"DDR4_SA_DQ17"
$PN"EM69"36;
"DDR4_SA_DQ18"
$PN"EN70"35;
"DDR4_SA_DQ19"
$PN"ER68"34;
"DDR4_SA_DQ20"
$PN"ER66"33;
"DDR4_SA_DQ21"
$PN"EM65"32;
"DDR4_SA_DQ22"
$PN"EL66"31;
"DDR4_SA_DQ23"
$PN"EP65"30;
"DDR4_SA_DQ24"
$PN"EM63"29;
"DDR4_SA_DQ25"
$PN"EL62"28;
"DDR4_SA_DQ26"
$PN"EP63"27;
"DDR4_SA_DQ27"
$PN"ER62"26;
"DDR4_SA_DQ28"
$PN"EL60"25;
"DDR4_SA_DQ29"
$PN"EM59"24;
"DDR4_SA_DQ30"
$PN"ER60"23;
"DDR4_SA_DQ31"
$PN"EP59"22;
"DDR4_SA_CS_N0 \B"
$PN"EP51"152;
"DDR4_SA_CS_N1 \B"
$PN"ET51"153;
"DDR4_SA_CS_N2 \B"
$PN"EM51"154;
"DDR4_SA_CS_N3 \B"
$PN"EL50"155;
"DDR4_SA_CA0"
$PN"EP49"156;
"DDR4_SA_CA1"
$PN"ET49"157;
"DDR4_SA_CA2"
$PN"EK49"158;
"DDR4_SA_CA3"
$PN"EL48"159;
"DDR4_SA_CA4"
$PN"EM47"160;
"DDR4_SA_CA5"
$PN"EP47"161;
"DDR4_SA_CA6"
$PN"ED44"162;
"DDR4_CLK_DP0"
$PN"EG45"21;
"DDR4_CLK_DP1"
$PN"EC45"20;
"DDR4_CLK_DN0 \B"
$PN"EJ45"19;
"DDR4_CLK_DN1 \B"
$PN"EE45"18;
"DDR4_B_RSP0"
$PN"DF44"163;
"DDR4_B_RSP1"
$PN"DG43"164;
"DDR4_A_RSP0"
$PN"DD44"165;
"DDR4_A_RSP1"
$PN"DC43"166;
"DDR4_ALERT_N \B"
$PN"CY47"167;
%"TAP"
"1","(-1075,2975)","2","standard","I70";
;
CDS_LIB"standard"
BODY_TYPE"PLUMBING"
HDL_TAP"TRUE";
"B \NAC \NWC"12;
"S \NAC"
BN"11"42;
%"TAP"
"1","(-1075,2925)","2","standard","I71";
;
CDS_LIB"standard"
BODY_TYPE"PLUMBING"
HDL_TAP"TRUE";
"B \NAC \NWC"12;
"S \NAC"
BN"10"43;
%"TAP"
"1","(-1075,3025)","2","standard","I72";
;
CDS_LIB"standard"
BODY_TYPE"PLUMBING"
HDL_TAP"TRUE";
"B \NAC \NWC"12;
"S \NAC"
BN"12"41;
%"TAP"
"1","(-1075,3075)","2","standard","I73";
;
CDS_LIB"standard"
BODY_TYPE"PLUMBING"
HDL_TAP"TRUE";
"B \NAC \NWC"12;
"S \NAC"
BN"13"40;
%"TAP"
"1","(-1075,3125)","2","standard","I74";
;
CDS_LIB"standard"
BODY_TYPE"PLUMBING"
HDL_TAP"TRUE";
"B \NAC \NWC"12;
"S \NAC"
BN"14"39;
%"TAP"
"1","(-1075,3175)","2","standard","I75";
;
CDS_LIB"standard"
BODY_TYPE"PLUMBING"
HDL_TAP"TRUE";
"B \NAC \NWC"12;
"S \NAC"
BN"15"38;
%"TAP"
"1","(-1075,3225)","2","standard","I76";
;
CDS_LIB"standard"
BODY_TYPE"PLUMBING"
HDL_TAP"TRUE";
"B \NAC \NWC"12;
"S \NAC"
BN"16"37;
%"TAP"
"1","(-1075,3275)","2","standard","I77";
;
CDS_LIB"standard"
BODY_TYPE"PLUMBING"
HDL_TAP"TRUE";
"B \NAC \NWC"12;
"S \NAC"
BN"17"36;
%"TAP"
"1","(-1075,3375)","2","standard","I78";
;
CDS_LIB"standard"
BODY_TYPE"PLUMBING"
HDL_TAP"TRUE";
"B \NAC \NWC"12;
"S \NAC"
BN"19"34;
%"TAP"
"1","(-1075,3325)","2","standard","I79";
;
CDS_LIB"standard"
BODY_TYPE"PLUMBING"
HDL_TAP"TRUE";
"B \NAC \NWC"12;
"S \NAC"
BN"18"35;
%"TAP"
"1","(-1075,3425)","2","standard","I80";
;
CDS_LIB"standard"
BODY_TYPE"PLUMBING"
HDL_TAP"TRUE";
"B \NAC \NWC"12;
"S \NAC"
BN"20"33;
%"TAP"
"1","(-1075,3475)","2","standard","I81";
;
CDS_LIB"standard"
BODY_TYPE"PLUMBING"
HDL_TAP"TRUE";
"B \NAC \NWC"12;
"S \NAC"
BN"21"32;
%"TAP"
"1","(-1075,3525)","2","standard","I82";
;
CDS_LIB"standard"
BODY_TYPE"PLUMBING"
HDL_TAP"TRUE";
"B \NAC \NWC"12;
"S \NAC"
BN"22"31;
%"TAP"
"1","(-1075,3575)","2","standard","I83";
;
CDS_LIB"standard"
BODY_TYPE"PLUMBING"
HDL_TAP"TRUE";
"B \NAC \NWC"12;
"S \NAC"
BN"23"30;
%"TAP"
"1","(-1075,3625)","2","standard","I84";
;
CDS_LIB"standard"
BODY_TYPE"PLUMBING"
HDL_TAP"TRUE";
"B \NAC \NWC"12;
"S \NAC"
BN"24"29;
%"TAP"
"1","(-1075,3675)","2","standard","I85";
;
CDS_LIB"standard"
BODY_TYPE"PLUMBING"
HDL_TAP"TRUE";
"B \NAC \NWC"12;
"S \NAC"
BN"25"28;
%"TAP"
"1","(-1075,3725)","2","standard","I86";
;
CDS_LIB"standard"
BODY_TYPE"PLUMBING"
HDL_TAP"TRUE";
"B \NAC \NWC"12;
"S \NAC"
BN"26"27;
%"TAP"
"1","(-1075,3775)","2","standard","I87";
;
CDS_LIB"standard"
BODY_TYPE"PLUMBING"
HDL_TAP"TRUE";
"B \NAC \NWC"12;
"S \NAC"
BN"27"26;
%"TAP"
"1","(-1075,3875)","2","standard","I88";
;
CDS_LIB"standard"
BODY_TYPE"PLUMBING"
HDL_TAP"TRUE";
"B \NAC \NWC"12;
"S \NAC"
BN"29"24;
%"TAP"
"1","(-1075,3825)","2","standard","I89";
;
CDS_LIB"standard"
BODY_TYPE"PLUMBING"
HDL_TAP"TRUE";
"B \NAC \NWC"12;
"S \NAC"
BN"28"25;
%"TAP"
"1","(-1075,3925)","2","standard","I90";
;
CDS_LIB"standard"
BODY_TYPE"PLUMBING"
HDL_TAP"TRUE";
"B \NAC \NWC"12;
"S \NAC"
BN"30"23;
%"TAP"
"1","(-1075,3975)","2","standard","I91";
;
CDS_LIB"standard"
BODY_TYPE"PLUMBING"
HDL_TAP"TRUE";
"B \NAC \NWC"12;
"S \NAC"
BN"31"22;
%"TAP"
"1","(2350,225)","0","standard","I95";
;
CDS_LIB"standard"
BODY_TYPE"PLUMBING"
HDL_TAP"TRUE";
"B \NAC \NWC"6;
"S \NAC"
BN"0"120;
%"TAP"
"1","(2350,325)","0","standard","I96";
;
CDS_LIB"standard"
BODY_TYPE"PLUMBING"
HDL_TAP"TRUE";
"B \NAC \NWC"6;
"S \NAC"
BN"2"122;
%"TAP"
"1","(2350,275)","0","standard","I97";
;
CDS_LIB"standard"
BODY_TYPE"PLUMBING"
HDL_TAP"TRUE";
"B \NAC \NWC"6;
"S \NAC"
BN"1"121;
%"TAP"
"1","(2350,375)","0","standard","I98";
;
CDS_LIB"standard"
BODY_TYPE"PLUMBING"
HDL_TAP"TRUE";
"B \NAC \NWC"6;
"S \NAC"
BN"3"123;
%"TAP"
"1","(2350,625)","0","standard","I99";
;
CDS_LIB"standard"
BODY_TYPE"PLUMBING"
HDL_TAP"TRUE";
"B \NAC \NWC"2;
"S \NAC"
BN"2"154;
END.
